# S9S_MB_2U (Grand Teton) — schematic netlist excerpt (pin names and nets, part order shuffled) for the footprints in the layout excerpt that follows; sources: Cadence DE-HDL packaged netlist, KiCad conversion of 03242023_DA0F0TMBIJ0_F0T_Motherboard_J_brd_V01_OCP.brd

R778  Q_RES  1K 1% CHIP  pkg 0402LF  page 131 : A = P3V3_AUX ; B = JTAG_DBP_BOOT_HALT_N
C207  Q_CAP  0.1UF 25V 10% X7R  pkg 0402  page 206 : A = P3V3_DB2000_VDD ; B = GND

(kicad_pcb
	(version 20260206)
	(generator "pcbnew")
	(generator_version "10.0")
	(general
		(thickness 1.6)
		(legacy_teardrops no)
	)
	(paper "A4")
	(title_block
		(title "03242023_DA0F0TMBIJ0_F0T_Motherboard_J_brd_V01_OCP.brd")
		(comment 1 "Grand Teton / footprints 5471-5472 of 6105")
	)
	(layers
		(0 "F.Cu" signal "TOP")
		(4 "In1.Cu" signal "GND")
		(6 "In2.Cu" signal "IN1")
		(8 "In3.Cu" signal "GND1")
		(10 "In4.Cu" signal "IN2")
		(12 "In5.Cu" signal "GND2")
		(14 "In6.Cu" signal "IN3")
		(16 "In7.Cu" signal "GND3")
		(18 "In8.Cu" signal "VCC")
		(20 "In9.Cu" signal "VCC1")
		(22 "In10.Cu" signal "GND4")
		(24 "In11.Cu" signal "IN4")
		(26 "In12.Cu" signal "GND5")
		(28 "In13.Cu" signal "IN5")
		(30 "In14.Cu" signal "GND6")
		(32 "In15.Cu" signal "IN6")
		(34 "In16.Cu" signal "GND7")
		(2 "B.Cu" signal "BOTTOM")
		(9 "F.Adhes" user "F.Adhesive")
		(11 "B.Adhes" user "B.Adhesive")
		(13 "F.Paste" user "Package Geometry/Pastemask Top")
		(15 "B.Paste" user "Package Geometry/Pastemask Bottom")
		(5 "F.SilkS" user "Ref Des/Silkscreen Top")
		(7 "B.SilkS" user "Ref Des/Silkscreen Bottom")
		(1 "F.Mask" user "Board Geometry/Soldermask Top")
		(3 "B.Mask" user "Board Geometry/Soldermask Bottom")
		(17 "Dwgs.User" user "User.Drawings")
		(19 "Cmts.User" user "User.Comments")
		(21 "Eco1.User" user "User.Eco1")
		(23 "Eco2.User" user "User.Eco2")
		(25 "Edge.Cuts" user "Board Geometry/Outline")
		(27 "Margin" user)
		(31 "F.CrtYd" user "Package Geometry/Place Bound Top")
		(29 "B.CrtYd" user "Package Geometry/Place Bound Bottom")
		(35 "F.Fab" user "Ref Des/Assembly Top")
		(33 "B.Fab" user "Ref Des/Assembly Bottom")
	)
	(footprint ""
		(layer "B.Cu")
		(at 237.837472 -128.518158 180)
		(property "Reference" "C207"
			(at 0 0 0)
			(layer "B.SilkS")
			(hide yes)
			(effects
				(font
					(size 1.27 1.27)
				)
				(justify mirror)
			)
		)
		(property "Value" ""
			(at 0 0 0)
			(layer "B.Fab")
			(effects
				(font
					(size 1.27 1.27)
				)
				(justify mirror)
			)
		)
		(duplicate_pad_numbers_are_jumpers no)
		(fp_line
			(start 0.7874 0.4064)
			(end 0.7874 -0.4064)
			(stroke
				(width 0.1524)
				(type default)
			)
			(layer "B.SilkS")
		)
		(fp_line
			(start 0.7874 -0.4064)
			(end -0.7874 -0.4064)
			(stroke
				(width 0.1524)
				(type default)
			)
			(layer "B.SilkS")
		)
		(fp_line
			(start -0.7874 0.4064)
			(end 0.7874 0.4064)
			(stroke
				(width 0.1524)
				(type default)
			)
			(layer "B.SilkS")
		)
		(fp_line
			(start -0.7874 -0.4064)
			(end -0.7874 0.4064)
			(stroke
				(width 0.1524)
				(type default)
			)
			(layer "B.SilkS")
		)
		(fp_line
			(start 0.67945 0.3048)
			(end 0.67945 -0.305054)
			(stroke
				(width 0.1)
				(type default)
			)
			(layer "B.Fab")
		)
		(fp_line
			(start 0.67945 -0.305054)
			(end 0.12065 -0.305054)
			(stroke
				(width 0.1)
				(type default)
			)
			(layer "B.Fab")
		)
		(fp_line
			(start 0.12065 0.3048)
			(end 0.67945 0.3048)
			(stroke
				(width 0.1)
				(type default)
			)
			(layer "B.Fab")
		)
		(fp_line
			(start 0.12065 0.2794)
			(end 0.12065 0.3048)
			(stroke
				(width 0.1)
				(type default)
			)
			(layer "B.Fab")
		)
		(fp_line
			(start 0.12065 -0.2794)
			(end -0.12065 -0.2794)
			(stroke
				(width 0.1)
				(type default)
			)
			(layer "B.Fab")
		)
		(fp_line
			(start 0.12065 -0.305054)
			(end 0.12065 -0.2794)
			(stroke
				(width 0.1)
				(type default)
			)
			(layer "B.Fab")
		)
		(fp_line
			(start -0.120396 0.3048)
			(end -0.120396 0.2794)
			(stroke
				(width 0.1)
				(type default)
			)
			(layer "B.Fab")
		)
		(fp_line
			(start -0.120396 0.2794)
			(end 0.12065 0.2794)
			(stroke
				(width 0.1)
				(type default)
			)
			(layer "B.Fab")
		)
		(fp_line
			(start -0.12065 -0.2794)
			(end -0.12065 -0.3048)
			(stroke
				(width 0.1)
				(type default)
			)
			(layer "B.Fab")
		)
		(fp_line
			(start -0.12065 -0.3048)
			(end -0.67945 -0.3048)
			(stroke
				(width 0.1)
				(type default)
			)
			(layer "B.Fab")
		)
		(fp_line
			(start -0.67945 0.3048)
			(end -0.120396 0.3048)
			(stroke
				(width 0.1)
				(type default)
			)
			(layer "B.Fab")
		)
		(fp_line
			(start -0.67945 -0.3048)
			(end -0.67945 0.3048)
			(stroke
				(width 0.1)
				(type default)
			)
			(layer "B.Fab")
		)
		(pad "1" smd circle
			(at 0.40005 0)
			(size 0 0)
			(layers "B.Cu" "B.Mask" "B.Paste")
			(net "P3V3_DB2000_VDD")
		)
		(pad "2" smd circle
			(at -0.40005 0)
			(size 0 0)
			(layers "B.Cu" "B.Mask" "B.Paste")
			(net "GND")
		)
	)
	(footprint ""
		(layer "B.Cu")
		(at 404.002748 -58.79846)
		(property "Reference" "R778"
			(at 0 0 0)
			(layer "B.SilkS")
			(hide yes)
			(effects
				(font
					(size 1.27 1.27)
				)
				(justify mirror)
			)
		)
		(property "Value" ""
			(at 0 0 0)
			(layer "B.Fab")
			(effects
				(font
					(size 1.27 1.27)
				)
				(justify mirror)
			)
		)
		(duplicate_pad_numbers_are_jumpers no)
		(fp_line
			(start -0.7874 -0.4064)
			(end -0.7874 0.4064)
			(stroke
				(width 0.1524)
				(type default)
			)
			(layer "B.SilkS")
		)
		(fp_line
			(start -0.7874 0.4064)
			(end 0.7874 0.4064)
			(stroke
				(width 0.1524)
				(type default)
			)
			(layer "B.SilkS")
		)
		(fp_line
			(start 0.7874 -0.4064)
			(end -0.7874 -0.4064)
			(stroke
				(width 0.1524)
				(type default)
			)
			(layer "B.SilkS")
		)
		(fp_line
			(start 0.7874 0.4064)
			(end 0.7874 -0.4064)
			(stroke
				(width 0.1524)
				(type default)
			)
			(layer "B.SilkS")
		)
		(fp_line
			(start -0.67945 -0.3048)
			(end -0.67945 0.3048)
			(stroke
				(width 0.1)
				(type default)
			)
			(layer "B.Fab")
		)
		(fp_line
			(start -0.67945 0.3048)
			(end -0.120396 0.3048)
			(stroke
				(width 0.1)
				(type default)
			)
			(layer "B.Fab")
		)
		(fp_line
			(start -0.12065 -0.3048)
			(end -0.67945 -0.3048)
			(stroke
				(width 0.1)
				(type default)
			)
			(layer "B.Fab")
		)
		(fp_line
			(start -0.12065 -0.2794)
			(end -0.12065 -0.3048)
			(stroke
				(width 0.1)
				(type default)
			)
			(layer "B.Fab")
		)
		(fp_line
			(start -0.120396 0.2794)
			(end 0.12065 0.2794)
			(stroke
				(width 0.1)
				(type default)
			)
			(layer "B.Fab")
		)
		(fp_line
			(start -0.120396 0.3048)
			(end -0.120396 0.2794)
			(stroke
				(width 0.1)
				(type default)
			)
			(layer "B.Fab")
		)
		(fp_line
			(start 0.12065 -0.305054)
			(end 0.12065 -0.2794)
			(stroke
				(width 0.1)
				(type default)
			)
			(layer "B.Fab")
		)
		(fp_line
			(start 0.12065 -0.2794)
			(end -0.12065 -0.2794)
			(stroke
				(width 0.1)
				(type default)
			)
			(layer "B.Fab")
		)
		(fp_line
			(start 0.12065 0.2794)
			(end 0.12065 0.3048)
			(stroke
				(width 0.1)
				(type default)
			)
			(layer "B.Fab")
		)
		(fp_line
			(start 0.12065 0.3048)
			(end 0.67945 0.3048)
			(stroke
				(width 0.1)
				(type default)
			)
			(layer "B.Fab")
		)
		(fp_line
			(start 0.67945 -0.305054)
			(end 0.12065 -0.305054)
			(stroke
				(width 0.1)
				(type default)
			)
			(layer "B.Fab")
		)
		(fp_line
			(start 0.67945 0.3048)
			(end 0.67945 -0.305054)
			(stroke
				(width 0.1)
				(type default)
			)
			(layer "B.Fab")
		)
		(pad "1" smd circle
			(at 0.40005 0 180)
			(size 0 0)
			(layers "B.Cu" "B.Mask" "B.Paste")
			(net "P3V3_AUX")
		)
		(pad "2" smd circle
			(at -0.40005 0 180)
			(size 0 0)
			(layers "B.Cu" "B.Mask" "B.Paste")
			(net "JTAG_DBP_BOOT_HALT_N")
		)
	)
)
